5
5
4
4
3
3
2
2
1
1
D D
C C
B B
A A
POWER TRANSITION BOARD 
Revision Histroy: 
DVT V04:2012/07/21 DVT Gerber Release 
Pulling Out 
Detection 
LED TX: LED16 
LED RX:Q31 
Board To Wire Connection 
4P20 CONN 
4x PWR/GND Pins 
20x Signals Pins 
36P24 Golden Finger 
36x PWR/GND Pins 
24x Signals Pins 
Slide Switch: SW1 
Green LED: LED1 
FCB 
Reserved I2C Buffer 
PCA9511 
Board To Board Connection 
DPB 
PVT V03:2012/10/16 PVT Gerber Release 
Title 
Size Document Number Rev 
Date: Sheet 
of 
KNOX_PTB 
-1 
BLOCK DIAGRAM 
A3 
1 5Friday, October 12, 2012 
Wiwynn 
H/W R&D Dept. II 
8F,90,Sec. 1,Hsin Tai Wu Rd, 
Hsichih, Taipei Hsien 221, Taiwan, R.O.C 
Title 
Size Document Number Rev 
Date: Sheet 
of 
KNOX_PTB 
-1 
BLOCK DIAGRAM 
A3 
1 5Friday, October 12, 2012 
Wiwynn 
H/W R&D Dept. II 
8F,90,Sec. 1,Hsin Tai Wu Rd, 
Hsichih, Taipei Hsien 221, Taiwan, R.O.C 
Title 
Size Document Number Rev 
Date: Sheet 
of 
KNOX_PTB 
-1 
BLOCK DIAGRAM 
A3 
1 5Friday, October 12, 2012 
Wiwynn 
H/W R&D Dept. II 
8F,90,Sec. 1,Hsin Tai Wu Rd, 
Hsichih, Taipei Hsien 221, Taiwan, R.O.C 



5
5
4
4
3
3
2
2
1
1
D D
C C
B B
A A
PIN Definition DY=Dummy parts 
  =not populated 
SCD1U10V2KX-5GP 
D1U = 0.1uF (2D2U means 2.2uF) 
10Voltage (6D3V means 6.3V) 
2 = size 0402, K tolerance 
K=tolerance 
[Wistron C code as below:] 
G=2% 
J=5% 
K=10% 
M=20% 
X=temp characteristics 
[Wistron C Series/Temp] 
N=NPO 
X=X7R/X5R 
Y=Y5V 
-5=different symbol/customer 
GP= Green Part (RoHS) 
562R2F- GP 
562 = 562 ohm, (2K2R means 2.2K ohm) 
2 = size 0402 
F = 1% tolerance 
GP= Green Part (RoHS) 
Wistron RC size code as below: 
1 = 0201 
2= 0402 
3= 0603 
5= 0805 
6= 1206 
Wistron R tolerance code as below: 
D=0.5% 
F= 1% 
J= 5% 
GCE 
Hannstar 
GCE 
Hannstar 
  PCB 
VENDOR 
12523-SA 
DVT BUILD 
PCBA_DIP 
PCBA_SMT 
PCB P/N 
PCB VER 
55.64W04.DA1G 
55.64W04.DA2G 
55.64W04.SA1G 
55.64W04.SA2G 
48.64W13.0SA GCE 
Hannstar 48.64W15.0SA 
Golden Finger 
To DPB 
4P20S 
To FCB 
DVT BUILD 
12523-1 
Title 
Size Document Number Rev 
Date: Sheet 
of 
KNOX_PTB 
-1 
PIN Definition 
A3 
2 5Friday, October 12, 2012 
Wiwynn 
H/W R&D Dept. II 
8F,90,Sec. 1,Hsin Tai Wu Rd, 
Hsichih, Taipei Hsien 221, Taiwan, R.O.C 
Title 
Size Document Number Rev 
Date: Sheet 
of 
KNOX_PTB 
-1 
PIN Definition 
A3 
2 5Friday, October 12, 2012 
Wiwynn 
H/W R&D Dept. II 
8F,90,Sec. 1,Hsin Tai Wu Rd, 
Hsichih, Taipei Hsien 221, Taiwan, R.O.C 
Title 
Size Document Number Rev 
Date: Sheet 
of 
KNOX_PTB 
-1 
PIN Definition 
A3 
2 5Friday, October 12, 2012 
Wiwynn 
H/W R&D Dept. II 
8F,90,Sec. 1,Hsin Tai Wu Rd, 
Hsichih, Taipei Hsien 221, Taiwan, R.O.C 



5
5
4
4
3
3
2
2
1
1
D D
C C
B B
A A
I2C_C_BUFFER 
PULLING OUT DETECTION 
EMITTER DETECTOR 
"H"=Tray is "pulling out" 
"L"=Tray is "inside the chassis" 
DVT 
20120711 
Remove reserve 
buffer PCA9507 
DVT 
20120719 
DVT 
20120717 
DVT 
20120717 
VF=1.3V 
IF=29mA 
FCB 
DPB DPB 
FCB 
DVT 
20120724 
I2C_C_BUF_SDAOUT 
I2C_C_BUF_EN 
I2C_C_BUF_SCLOUT 
EMITTER_K 
IR_switch_E 
TRAY_PRESENT_OUT_NET_B 
Tray present_OUT#_C 
I2C_C_BUF_SCLIN 
TRAY PRESENT_OUT_NET 
TRAY_MOSFET_G 
DETECTOR_C 
I2C_C_BUF_SDAIN 
I2C_C_BUF_READY 
P3V3 
P3V3 
P3V3 
P3V3 
P3V3 
P3V3 
P3V3 P5VA 
P3V3 
P3V3 
P3V3 
SELF_TRAY_PRESENT 4
I2C_C_SCL 4
I2C_C_BUF_SCL 4
I2C_C_SDA 4
I2C_C_BUF_SDA 4
Title 
Size Document Number Rev 
Date: Sheet 
of 
KNOX_PTB 
-1 
I2C_C BUFFER&PULLING OUT 
A3 
3 5Friday, October 12, 2012 
Wiwynn 
H/W R&D Dept. II 
8F,90,Sec. 1,Hsin Tai Wu Rd, 
Hsichih, Taipei Hsien 221, Taiwan, R.O.C 
Title 
Size Document Number Rev 
Date: Sheet 
of 
KNOX_PTB 
-1 
I2C_C BUFFER&PULLING OUT 
A3 
3 5Friday, October 12, 2012 
Wiwynn 
H/W R&D Dept. II 
8F,90,Sec. 1,Hsin Tai Wu Rd, 
Hsichih, Taipei Hsien 221, Taiwan, R.O.C 
Title 
Size Document Number Rev 
Date: Sheet 
of 
KNOX_PTB 
-1 
I2C_C BUFFER&PULLING OUT 
A3 
3 5Friday, October 12, 2012 
Wiwynn 
H/W R&D Dept. II 
8F,90,Sec. 1,Hsin Tai Wu Rd, 
Hsichih, Taipei Hsien 221, Taiwan, R.O.C 
C344 
SCD1U50V3KX-GP 
C344 
SCD1U50V3KX-GP 
1 2
R379 
10KR2F-2-GP 
R379 
10KR2F-2-GP 
1 2
R486 
0R2J-2-GP 
DY 
R486 
0R2J-2-GP 
DY 1 2
R480 
0R2J-2-GP 
R480 
0R2J-2-GP 
1 2
Q31 
SENSOR-2P-GP-U 
Q31 
SENSOR-2P-GP-U 
EC
R484 
0R2J-2-GP 
DY 
R484 
0R2J-2-GP 
DY 1 2
R485 
0R2J-2-GP 
DY 
R485 
0R2J-2-GP 
DY 1 2
R342 
10KR2F-2-GP 
R342 
10KR2F-2-GP 
1 2
R374 
470KR2F-GP 
R374 
470KR2F-GP 
1 2
LED16 
LED-IR-1-GP 
LED16 
LED-IR-1-GP 
A K
PR65 
0R3J-0-U-GP 
PR65 
0R3J-0-U-GP 
1 2
R369 
4K7R2J-2-GP 
DY R369 
4K7R2J-2-GP 
DY 
1 2
R376 
100KR2F-L1-GP 
R376 
100KR2F-L1-GP 
1 2R366 
0R2J-2-GP 
R366 
0R2J-2-GP 
1 2
U51 
PCA9511ADP-T-GP 
U51 
PCA9511ADP-T-GP 
ENABLE 1
SCLOUT 2
SCLIN 3
GND 4 READY 5SDAIN 6SDAOUT 7VCC 8
R365 
0R2J-2-GP 
DY 
R365 
0R2J-2-GP 
DY 
1 2
R378 
68R5J-GP 
R378 
68R5J-GP 
1 2
R370 
4K7R2J-2-GP 
DY R370 
4K7R2J-2-GP 
DY 
1 2
Q34 
2N7002-11-GP 
Q34 
2N7002-11-GP 
G
SD
PR64 
0R3J-0-U-GP 
DY PR64 
0R3J-0-U-GP 
DY 
1 2
Q33 
MMBT2222A-3-GP 
Q33 
MMBT2222A-3-GP 
C
B
E
R353 
10KR2F-2-GP 
R353 
10KR2F-2-GP 
1 2
R375 
100R2F-L1-GP-U 
R375 
100R2F-L1-GP-U 
1 2
R344 
10KR2F-2-GP 
R344 
10KR2F-2-GP 
1 2
R481 
0R2J-2-GP 
R481 
0R2J-2-GP 
1 2
R487 
0R2J-2-GP 
DY R487 
0R2J-2-GP 
DY 
1 2
R343 
10KR2F-2-GP 
R343 
10KR2F-2-GP 
1 2
R482 
0R2J-2-GP 
R482 
0R2J-2-GP 
1 2
TP9 
TPAD32-GP 
TP9 
TPAD32-GP 
1
C345 
SCD01U50V2KX-1GP 
C345 
SCD01U50V2KX-1GP 
1 2



5
5
4
4
3
3
2
2
1
1
D D
C C
B B
A A
TPS2490 PWR CONTROL 
4P20S PWR CONN 
SCREW HOLDs 
GOLDEN_FINGER 
Green LED 
Vf=2V, I=5mA 
DVT 
20120711 
DVT 
20120719 
DVT 
20120719 
DVT 
20120720 
PVT 
20121008 
PVT 
20121012 
PVT 
20121012 
PWM_EXP_B_OUT PWM_EXP_B 
SELF_1B&2B_HB 
PEER_TRAY_PRESENT 
TRAY_ID 
TRAY_ID 
SD_LATCH_RELEASE 
PEER_1A&2A_HB 
FCB_HW_REV 
SELF_1A&2A_HB 
SELF_1B&2B_HB 
PWM_EXP_B 
STRADDLE_I2C_C_SDA 
PWM_EXP_A 
TPS2490_LED 
PEER_1B&2B_HB 
SD_LATCH_RELEASE 
PEER_1A&2A_HB 
FCB_HW_REV 
PEER_TRAY_PRESENT PEER_1B&2B_HB 
PWM_EXP_A 
SELF_1A&2A_HB 
STRADDLE_I2C_C_SCL 
I2C_C_BUF_SDA_CONN 
PWM_EXP_A_OUT 
I2C_C_BUF_SDA_CONN 
I2C_C_BUF_SCL_CONN 
TPS2490_DISABLE 
I2C_C_BUF_SCL_CONN TPS2490_EN2 
TPS2490_EN1 
P12V 
P12V 
P12V 
P3V3 
P12V 
P5VA 
P12V 
I2C_C_BUF_SCL 3
SELF_TRAY_PRESENT 3
SELF_TRAY_PRESENT 3
I2C_C_SCL 3
I2C_C_SDA 3
I2C_C_BUF_SDA 3
Title 
Size Document Number Rev 
Date: Sheet 
of 
KNOX_PTB 
-1 
CONNs 
A3 
4 5Friday, October 12, 2012 
Wiwynn 
H/W R&D Dept. II 
8F,90,Sec. 1,Hsin Tai Wu Rd, 
Hsichih, Taipei Hsien 221, Taiwan, R.O.C 
Title 
Size Document Number Rev 
Date: Sheet 
of 
KNOX_PTB 
-1 
CONNs 
A3 
4 5Friday, October 12, 2012 
Wiwynn 
H/W R&D Dept. II 
8F,90,Sec. 1,Hsin Tai Wu Rd, 
Hsichih, Taipei Hsien 221, Taiwan, R.O.C 
Title 
Size Document Number Rev 
Date: Sheet 
of 
KNOX_PTB 
-1 
CONNs 
A3 
4 5Friday, October 12, 2012 
Wiwynn 
H/W R&D Dept. II 
8F,90,Sec. 1,Hsin Tai Wu Rd, 
Hsichih, Taipei Hsien 221, Taiwan, R.O.C 
R389 0R2J-2-GP R389 0R2J-2-GP 1 2
LED1 
LED-G-203-GP 
LED1 
LED-G-203-GP 
A K
R390 
0R2J-2-GP 
DY R390 
0R2J-2-GP 
DY 
1 2
C363 
SC47U16V0MX-GP 
DY C363 
SC47U16V0MX-GP 
DY 
1 2
C348 
SC10U25V5KX-GP 
C348 
SC10U25V5KX-GP 
1 2
TC5 
ST68U16VDM-1-GP 
TC5 
ST68U16VDM-1-GP 
1 2
C361 
SC47U16V0MX-GP 
DY C361 
SC47U16V0MX-GP 
DY 
1 2
R384 0R2J-2-GP R384 0R2J-2-GP 1 2
C364 
SC47U16V0MX-GP 
DY C364 
SC47U16V0MX-GP 
DY 
1 2
R483 
2KR3F-L-GP 
R483 
2KR3F-L-GP 
1 2
C358 
SC220P50V3JN-GP 
DY C358 
SC220P50V3JN-GP 
DY 
1 2
H3 
HOLE 
H3 
HOLE 
1
R391 
0R2J-2-GP 
R391 
0R2J-2-GP 
1 2
C357 
SC220P50V3JN-GP 
DY C357 
SC220P50V3JN-GP 
DY 
1 2
R388 0R2J-2-GP R388 0R2J-2-GP 1 2
TC3 
ST68U16VDM-1-GP 
TC3 
ST68U16VDM-1-GP 
1 2
C349 
SC10U25V5KX-GP 
C349 
SC10U25V5KX-GP 
1 2
C362 
SC47U16V0MX-GP 
DY C362 
SC47U16V0MX-GP 
DY 
1 2
H2 
HOLE 
H2 
HOLE 
1
TC4 
ST68U16VDM-1-GP 
TC4 
ST68U16VDM-1-GP 
1 2
R387 0R2J-2-GP R387 0R2J-2-GP 1 2
C360 
SC220P50V3JN-GP 
DY C360 
SC220P50V3JN-GP 
DY 
1 2
02 Do not mirror 
TOP BOTTOM 
GF1 
GF-36P-24P-GP 
02 Do not mirror 
TOP BOTTOM 
GF1 
GF-36P-24P-GP 
P18 P18 P17 P17 
P16 P16 P15 P15 P14 P14 P13 P13 
P12 P12 P11 P11 P10 P10 P9 P9 
P8 P8 P7 P7 P6 P6 P5 P5 
P4 P4 P3 P3 P2 P2 P1 P1 
P25 P25 P26 P26 P27 P27 P28 P28 
P29 P29 
P19 P19 P20 P20 
P21 P21 P22 P22 P23 P23 P24 P24 
S1 S1 
S2 S2 
S3 S3 
S4 S4 
S5 S5 
S6 S6 
S7 S7 
S8 S8 
S9 S9 
S10 S10 
S11 S11 
S12 S12 
S24 S24 
S23 S23 
S22 S22 
S21 S21 
S20 S20 
S19 S19 
S18 S18 
S17 S17 
S16 S16 
S15 S15 
S14 S14 
S13 S13 
P32 P32 
P31 P31 
P30 P30 
P36 P36 
P35 P35 
P34 P34 
P33 P33 
C359 
SC220P50V3JN-GP 
DY C359 
SC220P50V3JN-GP 
DY 
1 2
SW1 
SW-SLIDE3P-15-GP 
DY SW1 
SW-SLIDE3P-15-GP 
DY 
1
2
3
NP1 
NP2 
CN4 
FCI-CONN52-4R-GP 
CN4 
FCI-CONN52-4R-GP 
P1_1 
P1_2 P1_3 
P1_5 
P1_6 P1_7 
P1_8 
P2_1 
P2_2 P2_3 
P2_4 
P2_5 
P2_6 P2_7 
P2_8 
NP1 
NP2 
P3_2 
P3_1 
P3_5 
P3_6 
P3_3 
P3_4 
P3_8 
P3_7 
P4_2 
P4_1 
P4_5 
P4_6 
P4_3 
P4_4 
P4_8 
P4_7 
A1 
B1 C1 
D1 
A2 
B2 C2 
D2 
P1_4 
A3 
A4 
A5 
B3 
B4 
B5 
C3 
C4 
C5 
D3 
D4 
D5 R385 0R2J-2-GP R385 0R2J-2-GP 1 2
H1 
HOLE 
H1 
HOLE 
1
R386 0R2J-2-GP R386 0R2J-2-GP 1 2
C355 
SC10U25V5KX-GP 
C355 
SC10U25V5KX-GP 
1 2
H4 
HOLE 
H4 
HOLE 
1



5
5
4
4
3
3
2
2
1
1
D D
C C
B B
A A
V02: (<name>) 
2012/07/11 
1. Change C348 and C349 from 10U/16V to 10U/25V to have more voltage derating, sheet 4. 
2. I2C_C buffer circuitry fine tune for offset voltage improvement, sheet 3. 
    a.) remove reserved I2C buffer U55 PCA9507 and relative components, C365, C366, C364, C356 and R479. 
    b.) depopulate I2C buffer U51 PCA9511 and relative components R369, R370, R343, C345 and C344. 
2012/07/17 
V03: (<name>) 
1. Pulling out detection circuitry fine tune, sheet 3. 
    a.) Change dummy part R374 from 8.06K to 470K to enlarge the voltage of VB. 
    b.) Change R379 from 100K to 10K. 
V04: (<name>) 
2012/07/19 
1. Populate I2C_C buffer PCA9511 and relative components. 
     a.) Swap the IN/OUT direction, IN connects to FCB side, OUT connects to DPB. 
     b.) The PU resistors on DPB are R342 and R344, change the value of resistance from 4.7K to 10K. 
     c.) The PU resistors on FCB are R370 and R369, change the value of resistance from 10K to 4.7K, default is "Dummy". 
     d.) Add extra 0 ohm R484 and R487, default is "dummy', bypass the path of buffer. 
     e.) Correct the connection of "READY" pin, in PCA9525 , it is for direction selection, in PCA9511, it is ready pin. 
         It needs to tie 3.3V. 
2.  Reserve the location of damping R and bypass C, sheet 4. 
     a.) Reserve 220pF cap on location C359 and C360. 
     b.) Add 0 ohm R on location R388 and R389. 
2012/07/20 
1. Connect SW1 Pin 3 to GND via 0 ohm R390, it is used to make TPS2490 EN pins discharge quickly. 
2012/07/24 
1. There are two 0.1uF caps C344 and C345 on I2C_C buffer PCA9511 VCC, Change C345 from 0.1uF to 0.01uF, sheet 3 
PVT V01: (<name>) 
2012/10/08 
1.Remove slide switch function from PVT to avoid human switch it to wrong direction, sheet 04. 
   a.) De-populate SW1 and R390. 
   b.) Add 0402 package 0 ohm on location R391. 
PVT V02: (<name>) 
2012/10/09 
1. Add screw hole H5 for plastic CONN protector fix. 
PVT V03: (<name>) 
2012/10/12 
1. Remove screw hole H5, since it is NPTH not PTH, it is no need to have orcad symbol for NPTH, sheet 04. 
2. Reserve 47uF/16V ceramic caps, C361, C362, C363, C364 for inrush current improvement, sheet 04. 
Title 
Size Document Number Rev 
Date: Sheet 
of 
KNOX_PTB 
-1 
CHANGE HISTORY 
A3 
5 5Friday, October 12, 2012 
Wiwynn 
H/W R&D Dept. II 
8F,90,Sec. 1,Hsin Tai Wu Rd, 
Hsichih, Taipei Hsien 221, Taiwan, R.O.C 
Title 
Size Document Number Rev 
Date: Sheet 
of 
KNOX_PTB 
-1 
CHANGE HISTORY 
A3 
5 5Friday, October 12, 2012 
Wiwynn 
H/W R&D Dept. II 
8F,90,Sec. 1,Hsin Tai Wu Rd, 
Hsichih, Taipei Hsien 221, Taiwan, R.O.C 
Title 
Size Document Number Rev 
Date: Sheet 
of 
KNOX_PTB 
-1 
CHANGE HISTORY 
A3 
5 5Friday, October 12, 2012 
Wiwynn 
H/W R&D Dept. II 
8F,90,Sec. 1,Hsin Tai Wu Rd, 
Hsichih, Taipei Hsien 221, Taiwan, R.O.C 